# T6G (Grand Teton) — schematic netlist excerpt (pin names and nets, part order shuffled) for the footprints in the layout excerpt that follows; sources: Cadence DE-HDL packaged netlist, KiCad conversion of 04192023_DAF0TMB3IC0_F0TG_MB_C_brd_V02_OCP.brd

R6143  Q_RES  1K 1% CHIP  pkg 0402LF  page 84 : A = FM_BOARD_BMC_SKU_ID2 ; B = GND
C2428  Q_CAP  22UF 4V 20% X6S  pkg C0402  page 74 : A = PVDDCR_SOC_P1 ; B = GND
PC8007  Q_CAP  22UF 16V 20% X6S  pkg C0805  page 225 : A = SW_P12V_AUX_PVDD11_S3_P1_FLT ; B = GND

(kicad_pcb
	(version 20260206)
	(generator "pcbnew")
	(generator_version "10.0")
	(general
		(thickness 1.6)
		(legacy_teardrops no)
	)
	(paper "A4")
	(title_block
		(title "04192023_DAF0TMB3IC0_F0TG_MB_C_brd_V02_OCP.brd")
		(comment 1 "Grand Teton / footprints 846-848 of 8354")
	)
	(layers
		(0 "F.Cu" signal "TOP")
		(4 "In1.Cu" signal "GND")
		(6 "In2.Cu" signal "IN1")
		(8 "In3.Cu" signal "GND1")
		(10 "In4.Cu" signal "IN2")
		(12 "In5.Cu" signal "GND2")
		(14 "In6.Cu" signal "IN3")
		(16 "In7.Cu" signal "GND3")
		(18 "In8.Cu" signal "VCC")
		(20 "In9.Cu" signal "VCC1")
		(22 "In10.Cu" signal "GND4")
		(24 "In11.Cu" signal "IN4")
		(26 "In12.Cu" signal "GND5")
		(28 "In13.Cu" signal "IN5")
		(30 "In14.Cu" signal "GND6")
		(32 "In15.Cu" signal "IN6")
		(34 "In16.Cu" signal "GND7")
		(2 "B.Cu" signal "BOTTOM")
		(9 "F.Adhes" user "F.Adhesive")
		(11 "B.Adhes" user "B.Adhesive")
		(13 "F.Paste" user "Package Geometry/Pastemask Top")
		(15 "B.Paste" user "Package Geometry/Pastemask Bottom")
		(5 "F.SilkS" user "Ref Des/Silkscreen Top")
		(7 "B.SilkS" user "Ref Des/Silkscreen Bottom")
		(1 "F.Mask" user "Board Geometry/Soldermask Top")
		(3 "B.Mask" user "Board Geometry/Soldermask Bottom")
		(17 "Dwgs.User" user "User.Drawings")
		(19 "Cmts.User" user "User.Comments")
		(21 "Eco1.User" user "User.Eco1")
		(23 "Eco2.User" user "User.Eco2")
		(25 "Edge.Cuts" user "Board Geometry/Outline")
		(27 "Margin" user)
		(31 "F.CrtYd" user "Package Geometry/Place Bound Top")
		(29 "B.CrtYd" user "Package Geometry/Place Bound Bottom")
		(35 "F.Fab" user "Ref Des/Assembly Top")
		(33 "B.Fab" user "Ref Des/Assembly Bottom")
	)
	(footprint ""
		(layer "F.Cu")
		(at 171.204128 -123.683268 180)
		(property "Reference" "R6143"
			(at 0 0 180)
			(layer "F.SilkS")
			(hide yes)
			(effects
				(font
					(size 1.27 1.27)
				)
			)
		)
		(property "Value" ""
			(at 0 0 180)
			(layer "F.Fab")
			(effects
				(font
					(size 1.27 1.27)
				)
			)
		)
		(duplicate_pad_numbers_are_jumpers no)
		(fp_line
			(start 0.7874 0.4064)
			(end -0.7874 0.4064)
			(stroke
				(width 0.1524)
				(type default)
			)
			(layer "F.SilkS")
		)
		(fp_line
			(start 0.7874 -0.4064)
			(end 0.7874 0.4064)
			(stroke
				(width 0.1524)
				(type default)
			)
			(layer "F.SilkS")
		)
		(fp_line
			(start -0.7874 0.4064)
			(end -0.7874 -0.4064)
			(stroke
				(width 0.1524)
				(type default)
			)
			(layer "F.SilkS")
		)
		(fp_line
			(start -0.7874 -0.4064)
			(end 0.7874 -0.4064)
			(stroke
				(width 0.1524)
				(type default)
			)
			(layer "F.SilkS")
		)
		(fp_line
			(start 0.67945 0.3048)
			(end 0.120396 0.3048)
			(stroke
				(width 0.1)
				(type default)
			)
			(layer "F.Fab")
		)
		(fp_line
			(start 0.67945 -0.3048)
			(end 0.67945 0.3048)
			(stroke
				(width 0.1)
				(type default)
			)
			(layer "F.Fab")
		)
		(fp_line
			(start 0.12065 -0.2794)
			(end 0.12065 -0.3048)
			(stroke
				(width 0.1)
				(type default)
			)
			(layer "F.Fab")
		)
		(fp_line
			(start 0.12065 -0.3048)
			(end 0.67945 -0.3048)
			(stroke
				(width 0.1)
				(type default)
			)
			(layer "F.Fab")
		)
		(fp_line
			(start 0.120396 0.3048)
			(end 0.120396 0.2794)
			(stroke
				(width 0.1)
				(type default)
			)
			(layer "F.Fab")
		)
		(fp_line
			(start 0.120396 0.2794)
			(end -0.12065 0.2794)
			(stroke
				(width 0.1)
				(type default)
			)
			(layer "F.Fab")
		)
		(fp_line
			(start -0.12065 0.3048)
			(end -0.67945 0.3048)
			(stroke
				(width 0.1)
				(type default)
			)
			(layer "F.Fab")
		)
		(fp_line
			(start -0.12065 0.2794)
			(end -0.12065 0.3048)
			(stroke
				(width 0.1)
				(type default)
			)
			(layer "F.Fab")
		)
		(fp_line
			(start -0.12065 -0.2794)
			(end 0.12065 -0.2794)
			(stroke
				(width 0.1)
				(type default)
			)
			(layer "F.Fab")
		)
		(fp_line
			(start -0.12065 -0.305054)
			(end -0.12065 -0.2794)
			(stroke
				(width 0.1)
				(type default)
			)
			(layer "F.Fab")
		)
		(fp_line
			(start -0.67945 0.3048)
			(end -0.67945 -0.305054)
			(stroke
				(width 0.1)
				(type default)
			)
			(layer "F.Fab")
		)
		(fp_line
			(start -0.67945 -0.305054)
			(end -0.12065 -0.305054)
			(stroke
				(width 0.1)
				(type default)
			)
			(layer "F.Fab")
		)
		(pad "1" smd circle
			(at -0.40005 0 180)
			(size 0 0)
			(layers "F.Cu" "F.Mask" "F.Paste")
			(net "FM_BOARD_BMC_SKU_ID2")
		)
		(pad "2" smd circle
			(at 0.40005 0 180)
			(size 0 0)
			(layers "F.Cu" "F.Mask" "F.Paste")
			(net "GND")
		)
	)
	(footprint ""
		(layer "F.Cu")
		(at 115.70589 -258.795266)
		(property "Reference" "C2428"
			(at 0 0 0)
			(layer "F.SilkS")
			(hide yes)
			(effects
				(font
					(size 1.27 1.27)
				)
			)
		)
		(property "Value" ""
			(at 0 0 0)
			(layer "F.Fab")
			(effects
				(font
					(size 1.27 1.27)
				)
			)
		)
		(duplicate_pad_numbers_are_jumpers no)
		(fp_line
			(start -0.7874 -0.4064)
			(end 0.7874 -0.4064)
			(stroke
				(width 0.1524)
				(type default)
			)
			(layer "F.SilkS")
		)
		(fp_line
			(start -0.7874 0.4064)
			(end -0.7874 -0.4064)
			(stroke
				(width 0.1524)
				(type default)
			)
			(layer "F.SilkS")
		)
		(fp_line
			(start 0.7874 -0.4064)
			(end 0.7874 0.4064)
			(stroke
				(width 0.1524)
				(type default)
			)
			(layer "F.SilkS")
		)
		(fp_line
			(start 0.7874 0.4064)
			(end -0.7874 0.4064)
			(stroke
				(width 0.1524)
				(type default)
			)
			(layer "F.SilkS")
		)
		(fp_line
			(start -0.67945 -0.305054)
			(end -0.12065 -0.305054)
			(stroke
				(width 0.1)
				(type default)
			)
			(layer "F.Fab")
		)
		(fp_line
			(start -0.67945 0.3048)
			(end -0.67945 -0.305054)
			(stroke
				(width 0.1)
				(type default)
			)
			(layer "F.Fab")
		)
		(fp_line
			(start -0.12065 -0.305054)
			(end -0.12065 -0.2794)
			(stroke
				(width 0.1)
				(type default)
			)
			(layer "F.Fab")
		)
		(fp_line
			(start -0.12065 -0.2794)
			(end 0.12065 -0.2794)
			(stroke
				(width 0.1)
				(type default)
			)
			(layer "F.Fab")
		)
		(fp_line
			(start -0.12065 0.2794)
			(end -0.12065 0.3048)
			(stroke
				(width 0.1)
				(type default)
			)
			(layer "F.Fab")
		)
		(fp_line
			(start -0.12065 0.3048)
			(end -0.67945 0.3048)
			(stroke
				(width 0.1)
				(type default)
			)
			(layer "F.Fab")
		)
		(fp_line
			(start 0.120396 0.2794)
			(end -0.12065 0.2794)
			(stroke
				(width 0.1)
				(type default)
			)
			(layer "F.Fab")
		)
		(fp_line
			(start 0.120396 0.3048)
			(end 0.120396 0.2794)
			(stroke
				(width 0.1)
				(type default)
			)
			(layer "F.Fab")
		)
		(fp_line
			(start 0.12065 -0.3048)
			(end 0.67945 -0.3048)
			(stroke
				(width 0.1)
				(type default)
			)
			(layer "F.Fab")
		)
		(fp_line
			(start 0.12065 -0.2794)
			(end 0.12065 -0.3048)
			(stroke
				(width 0.1)
				(type default)
			)
			(layer "F.Fab")
		)
		(fp_line
			(start 0.67945 -0.3048)
			(end 0.67945 0.3048)
			(stroke
				(width 0.1)
				(type default)
			)
			(layer "F.Fab")
		)
		(fp_line
			(start 0.67945 0.3048)
			(end 0.120396 0.3048)
			(stroke
				(width 0.1)
				(type default)
			)
			(layer "F.Fab")
		)
		(pad "1" smd circle
			(at -0.40005 0)
			(size 0 0)
			(layers "F.Cu" "F.Mask" "F.Paste")
			(net "PVDDCR_SOC_P1")
		)
		(pad "2" smd circle
			(at 0.40005 0)
			(size 0 0)
			(layers "F.Cu" "F.Mask" "F.Paste")
			(net "GND")
		)
	)
	(footprint ""
		(layer "F.Cu")
		(at 197.610476 -358.027478)
		(property "Reference" "PC8007"
			(at 0 0 0)
			(layer "F.SilkS")
			(hide yes)
			(effects
				(font
					(size 1.27 1.27)
				)
			)
		)
		(property "Value" ""
			(at 0 0 0)
			(layer "F.Fab")
			(effects
				(font
					(size 1.27 1.27)
				)
			)
		)
		(duplicate_pad_numbers_are_jumpers no)
		(fp_line
			(start -1.524 -0.762)
			(end 1.524 -0.762)
			(stroke
				(width 0.1524)
				(type default)
			)
			(layer "F.SilkS")
		)
		(fp_line
			(start -1.524 0.762)
			(end -1.524 -0.762)
			(stroke
				(width 0.1524)
				(type default)
			)
			(layer "F.SilkS")
		)
		(fp_line
			(start 1.524 -0.762)
			(end 1.524 0.762)
			(stroke
				(width 0.1524)
				(type default)
			)
			(layer "F.SilkS")
		)
		(fp_line
			(start 1.524 0.762)
			(end -1.524 0.762)
			(stroke
				(width 0.1524)
				(type default)
			)
			(layer "F.SilkS")
		)
		(fp_line
			(start -1.1049 -0.724916)
			(end -1.1049 0.724916)
			(stroke
				(width 0.1)
				(type default)
			)
			(layer "F.Fab")
		)
		(fp_line
			(start -1.1049 0.724916)
			(end 1.1049 0.724916)
			(stroke
				(width 0.1)
				(type default)
			)
			(layer "F.Fab")
		)
		(fp_line
			(start 1.1049 -0.724916)
			(end -1.1049 -0.724916)
			(stroke
				(width 0.1)
				(type default)
			)
			(layer "F.Fab")
		)
		(fp_line
			(start 1.1049 0.724916)
			(end 1.1049 -0.724916)
			(stroke
				(width 0.1)
				(type default)
			)
			(layer "F.Fab")
		)
		(pad "1" smd rect
			(at -0.889 0 180)
			(size 1.016 1.27)
			(layers "F.Cu" "F.Mask" "F.Paste")
			(net "SW_P12V_AUX_PVDD11_S3_P1_FLT")
		)
		(pad "2" smd rect
			(at 0.889 0 180)
			(size 1.016 1.27)
			(layers "F.Cu" "F.Mask" "F.Paste")
			(net "GND")
		)
	)
)
